# T6G (Grand Teton) — schematic netlist excerpt (pin names and nets, part order shuffled) for the footprints in the layout excerpt that follows; sources: Cadence DE-HDL packaged netlist, KiCad conversion of 04192023_DAF0TMB3IC0_F0TG_MB_C_brd_V02_OCP.brd

R3275  Q_RES  1K 1% EMPTY  pkg 0402LF  page 111 : A = P3V3_AUX ; B = FM_P2E_FGA

PU6500  MPQ8633BGLEC838Z  MPQ8633BGLE-C838-Z IC  pkg QFN14_4X3  page 360
  BST  = SW_P1V8_RETIMER_CPU0_BST
  AGND  = GND
  CS  = P1V8_RETIMER_CPU0_CS
  MODE  = P1V8_RETIMER_CPU0_MODE
  TRK_REF  = P1V8_RETIMER_CPU0_REF
  RGND  = GND
  FB  = P1V8_RETIMER_CPU0_FB
  EN  = P1V8_RETIMER_CPU0_EN
  PGOOD  = PWRGD_P1V8_RETIMER_CPU0
  VIN1  = SW_P12V_AUX_P1V8_RETIMER_CPU0_FLT
  PGND  = GND
  VCC  = P1V8_RETIMER_CPU0_VCC
  SW  = SW_P1V8_RETIMER_CPU0_SW
  VIN2  = SW_P12V_AUX_P1V8_RETIMER_CPU0_FLT

(kicad_pcb
	(version 20260206)
	(generator "pcbnew")
	(generator_version "10.0")
	(general
		(thickness 1.6)
		(legacy_teardrops no)
	)
	(paper "A4")
	(title_block
		(title "04192023_DAF0TMB3IC0_F0TG_MB_C_brd_V02_OCP.brd")
		(comment 1 "Grand Teton / footprints 1911-1912 of 8354")
	)
	(layers
		(0 "F.Cu" signal "TOP")
		(4 "In1.Cu" signal "GND")
		(6 "In2.Cu" signal "IN1")
		(8 "In3.Cu" signal "GND1")
		(10 "In4.Cu" signal "IN2")
		(12 "In5.Cu" signal "GND2")
		(14 "In6.Cu" signal "IN3")
		(16 "In7.Cu" signal "GND3")
		(18 "In8.Cu" signal "VCC")
		(20 "In9.Cu" signal "VCC1")
		(22 "In10.Cu" signal "GND4")
		(24 "In11.Cu" signal "IN4")
		(26 "In12.Cu" signal "GND5")
		(28 "In13.Cu" signal "IN5")
		(30 "In14.Cu" signal "GND6")
		(32 "In15.Cu" signal "IN6")
		(34 "In16.Cu" signal "GND7")
		(2 "B.Cu" signal "BOTTOM")
		(9 "F.Adhes" user "F.Adhesive")
		(11 "B.Adhes" user "B.Adhesive")
		(13 "F.Paste" user "Package Geometry/Pastemask Top")
		(15 "B.Paste" user "Package Geometry/Pastemask Bottom")
		(5 "F.SilkS" user "Ref Des/Silkscreen Top")
		(7 "B.SilkS" user "Ref Des/Silkscreen Bottom")
		(1 "F.Mask" user "Board Geometry/Soldermask Top")
		(3 "B.Mask" user "Board Geometry/Soldermask Bottom")
		(17 "Dwgs.User" user "User.Drawings")
		(19 "Cmts.User" user "User.Comments")
		(21 "Eco1.User" user "User.Eco1")
		(23 "Eco2.User" user "User.Eco2")
		(25 "Edge.Cuts" user "Board Geometry/Outline")
		(27 "Margin" user)
		(31 "F.CrtYd" user "Package Geometry/Place Bound Top")
		(29 "B.CrtYd" user "Package Geometry/Place Bound Bottom")
		(35 "F.Fab" user "Ref Des/Assembly Top")
		(33 "B.Fab" user "Ref Des/Assembly Bottom")
	)
	(footprint ""
		(layer "F.Cu")
		(at 33.617662 -419.249098 90)
		(property "Reference" "R3275"
			(at 0 0 90)
			(layer "F.SilkS")
			(hide yes)
			(effects
				(font
					(size 1.27 1.27)
				)
			)
		)
		(property "Value" ""
			(at 0 0 90)
			(layer "F.Fab")
			(effects
				(font
					(size 1.27 1.27)
				)
			)
		)
		(duplicate_pad_numbers_are_jumpers no)
		(fp_line
			(start 0.7874 -0.4064)
			(end 0.7874 0.4064)
			(stroke
				(width 0.1524)
				(type default)
			)
			(layer "F.SilkS")
		)
		(fp_line
			(start -0.7874 -0.4064)
			(end 0.7874 -0.4064)
			(stroke
				(width 0.1524)
				(type default)
			)
			(layer "F.SilkS")
		)
		(fp_line
			(start 0.7874 0.4064)
			(end -0.7874 0.4064)
			(stroke
				(width 0.1524)
				(type default)
			)
			(layer "F.SilkS")
		)
		(fp_line
			(start -0.7874 0.4064)
			(end -0.7874 -0.4064)
			(stroke
				(width 0.1524)
				(type default)
			)
			(layer "F.SilkS")
		)
		(fp_line
			(start -0.12065 -0.305054)
			(end -0.12065 -0.2794)
			(stroke
				(width 0.1)
				(type default)
			)
			(layer "F.Fab")
		)
		(fp_line
			(start -0.67945 -0.305054)
			(end -0.12065 -0.305054)
			(stroke
				(width 0.1)
				(type default)
			)
			(layer "F.Fab")
		)
		(fp_line
			(start 0.67945 -0.3048)
			(end 0.67945 0.3048)
			(stroke
				(width 0.1)
				(type default)
			)
			(layer "F.Fab")
		)
		(fp_line
			(start 0.12065 -0.3048)
			(end 0.67945 -0.3048)
			(stroke
				(width 0.1)
				(type default)
			)
			(layer "F.Fab")
		)
		(fp_line
			(start 0.12065 -0.2794)
			(end 0.12065 -0.3048)
			(stroke
				(width 0.1)
				(type default)
			)
			(layer "F.Fab")
		)
		(fp_line
			(start -0.12065 -0.2794)
			(end 0.12065 -0.2794)
			(stroke
				(width 0.1)
				(type default)
			)
			(layer "F.Fab")
		)
		(fp_line
			(start 0.120396 0.2794)
			(end -0.12065 0.2794)
			(stroke
				(width 0.1)
				(type default)
			)
			(layer "F.Fab")
		)
		(fp_line
			(start -0.12065 0.2794)
			(end -0.12065 0.3048)
			(stroke
				(width 0.1)
				(type default)
			)
			(layer "F.Fab")
		)
		(fp_line
			(start 0.67945 0.3048)
			(end 0.120396 0.3048)
			(stroke
				(width 0.1)
				(type default)
			)
			(layer "F.Fab")
		)
		(fp_line
			(start 0.120396 0.3048)
			(end 0.120396 0.2794)
			(stroke
				(width 0.1)
				(type default)
			)
			(layer "F.Fab")
		)
		(fp_line
			(start -0.12065 0.3048)
			(end -0.67945 0.3048)
			(stroke
				(width 0.1)
				(type default)
			)
			(layer "F.Fab")
		)
		(fp_line
			(start -0.67945 0.3048)
			(end -0.67945 -0.305054)
			(stroke
				(width 0.1)
				(type default)
			)
			(layer "F.Fab")
		)
		(pad "1" smd circle
			(at -0.40005 0 90)
			(size 0 0)
			(layers "F.Cu" "F.Mask" "F.Paste")
			(net "P3V3_AUX")
		)
		(pad "2" smd circle
			(at 0.40005 0 90)
			(size 0 0)
			(layers "F.Cu" "F.Mask" "F.Paste")
			(net "FM_P2E_FGA")
		)
	)
	(footprint ""
		(layer "F.Cu")
		(at 243.37137 -291.761926)
		(property "Reference" "PU6500"
			(at 0.786384 -3.70332 0)
			(unlocked yes)
			(layer "F.SilkS")
			(effects
				(font
					(size 0.7874 0.5842)
					(thickness 0.1524)
				)
				(justify left)
			)
		)
		(property "Value" ""
			(at 0 0 0)
			(layer "F.Fab")
			(effects
				(font
					(size 1.27 1.27)
				)
			)
		)
		(duplicate_pad_numbers_are_jumpers no)
		(fp_line
			(start -1.549908 -2.050034)
			(end -1.549908 -1.9812)
			(stroke
				(width 0.1524)
				(type default)
			)
			(layer "F.SilkS")
		)
		(fp_line
			(start -1.549908 1.9812)
			(end -1.549908 2.050034)
			(stroke
				(width 0.1524)
				(type default)
			)
			(layer "F.SilkS")
		)
		(fp_line
			(start -1.549908 2.050034)
			(end -0.5842 2.050034)
			(stroke
				(width 0.1524)
				(type default)
			)
			(layer "F.SilkS")
		)
		(fp_line
			(start -0.5842 -2.050034)
			(end -1.549908 -2.050034)
			(stroke
				(width 0.1524)
				(type default)
			)
			(layer "F.SilkS")
		)
		(fp_line
			(start 0 2.050034)
			(end 1.549908 2.050034)
			(stroke
				(width 0.1524)
				(type default)
			)
			(layer "F.SilkS")
		)
		(fp_line
			(start 1.549908 -2.050034)
			(end 0.5842 -2.050034)
			(stroke
				(width 0.1524)
				(type default)
			)
			(layer "F.SilkS")
		)
		(fp_line
			(start 1.549908 -1.9812)
			(end 1.549908 -2.050034)
			(stroke
				(width 0.1524)
				(type default)
			)
			(layer "F.SilkS")
		)
		(fp_line
			(start 1.549908 2.050034)
			(end 1.549908 1.9304)
			(stroke
				(width 0.1524)
				(type default)
			)
			(layer "F.SilkS")
		)
		(fp_poly
			(pts
				(xy -2.9464 -2.208022) (xy -2.9464 -1.192022) (xy -1.9304 -1.700022)
			)
			(stroke
				(width 0)
				(type default)
			)
			(fill yes)
			(layer "F.SilkS")
		)
		(fp_line
			(start -1.549908 -2.050034)
			(end -1.549908 2.050034)
			(stroke
				(width 0.1)
				(type default)
			)
			(layer "F.Fab")
		)
		(fp_line
			(start -1.549908 2.050034)
			(end 1.549908 2.050034)
			(stroke
				(width 0.1)
				(type default)
			)
			(layer "F.Fab")
		)
		(fp_line
			(start 1.549908 -2.050034)
			(end -1.549908 -2.050034)
			(stroke
				(width 0.1)
				(type default)
			)
			(layer "F.Fab")
		)
		(fp_line
			(start 1.549908 2.050034)
			(end 1.549908 -2.050034)
			(stroke
				(width 0.1)
				(type default)
			)
			(layer "F.Fab")
		)
		(fp_poly
			(pts
				(xy -2.9464 -2.208022) (xy -2.9464 -1.192022) (xy -1.9304 -1.700022)
			)
			(stroke
				(width 0)
				(type default)
			)
			(fill yes)
			(layer "F.Fab")
		)
		(pad "1" smd circle
			(at -1.35001 -1.700022)
			(size 0 0)
			(layers "F.Cu" "F.Mask" "F.Paste")
			(net "SW_P1V8_RETIMER_CPU0_BST")
		)
		(pad "2" smd rect
			(at -1.400048 -1.199896 90)
			(size 0.1778 0.8128)
			(layers "F.Cu" "F.Mask" "F.Paste")
			(net "GND")
		)
		(pad "3" smd rect
			(at -1.400048 -0.8001 90)
			(size 0.1778 0.8128)
			(layers "F.Cu" "F.Mask" "F.Paste")
			(net "P1V8_RETIMER_CPU0_CS")
		)
		(pad "4" smd rect
			(at -1.400048 -0.40005 90)
			(size 0.1778 0.8128)
			(layers "F.Cu" "F.Mask" "F.Paste")
			(net "P1V8_RETIMER_CPU0_MODE")
		)
		(pad "5" smd rect
			(at -1.400048 0 90)
			(size 0.1778 0.8128)
			(layers "F.Cu" "F.Mask" "F.Paste")
			(net "P1V8_RETIMER_CPU0_REF")
		)
		(pad "6" smd rect
			(at -1.400048 0.40005 90)
			(size 0.1778 0.8128)
			(layers "F.Cu" "F.Mask" "F.Paste")
			(net "GND")
		)
		(pad "7" smd rect
			(at -1.400048 0.8001 90)
			(size 0.1778 0.8128)
			(layers "F.Cu" "F.Mask" "F.Paste")
			(net "P1V8_RETIMER_CPU0_FB")
		)
		(pad "8" smd rect
			(at -1.400048 1.199896 90)
			(size 0.1778 0.8128)
			(layers "F.Cu" "F.Mask" "F.Paste")
			(net "P1V8_RETIMER_CPU0_EN")
		)
		(pad "9" smd rect
			(at -1.400048 1.700022 90)
			(size 0.3048 0.8128)
			(layers "F.Cu" "F.Mask" "F.Paste")
			(net "PWRGD_P1V8_RETIMER_CPU0")
		)
		(pad "10" smd rect
			(at -0.299974 1.299972)
			(size 0.3048 2.0066)
			(layers "F.Cu" "F.Mask" "F.Paste")
			(net "SW_P12V_AUX_P1V8_RETIMER_CPU0_FLT")
		)
		(pad "11_18" smd circle
			(at 1.175004 0.275082)
			(size 0 0)
			(layers "F.Cu" "F.Mask" "F.Paste")
			(net "GND")
		)
		(pad "19" smd rect
			(at 1.400048 -1.700022 270)
			(size 0.3048 0.8128)
			(layers "F.Cu" "F.Mask" "F.Paste")
			(net "P1V8_RETIMER_CPU0_VCC")
		)
		(pad "20" smd rect
			(at 0.299974 -1.299972)
			(size 0.3048 2.0066)
			(layers "F.Cu" "F.Mask" "F.Paste")
			(net "SW_P1V8_RETIMER_CPU0_SW")
		)
		(pad "21" smd rect
			(at -0.299974 -1.299972)
			(size 0.3048 2.0066)
			(layers "F.Cu" "F.Mask" "F.Paste")
			(net "SW_P12V_AUX_P1V8_RETIMER_CPU0_FLT")
		)
	)
)
